# S9S_MB_2U (Grand Teton) — schematic netlist excerpt (pin names and nets, part order shuffled) for the footprints in the layout excerpt that follows; sources: Cadence DE-HDL packaged netlist, KiCad conversion of 03242023_DA0F0TMBIJ0_F0T_Motherboard_J_brd_V01_OCP.brd

PR171  Q_RES  0 5% CHIP  pkg 0402LF  page 266 : A = PVCCIN_CPU0_ADDR ; B = GND
C335  Q_CAP  47UF 4V 20% X6S  pkg C0805  page 78 : A = PVCCIN_CPU1 ; B = GND
R2423  Q_RES  33.2 1% CHIP  pkg 0402LF  page 240 : A = SMB_SML1_PMBUS_3V3AUX_PCH_SCL ; B = SMB_SML1_PMBUS_3V3AUX_PCH_SCL_R

(kicad_pcb
	(version 20260206)
	(generator "pcbnew")
	(generator_version "10.0")
	(general
		(thickness 1.6)
		(legacy_teardrops no)
	)
	(paper "A4")
	(title_block
		(title "03242023_DA0F0TMBIJ0_F0T_Motherboard_J_brd_V01_OCP.brd")
		(comment 1 "Grand Teton / footprints 4257-4259 of 6105")
	)
	(layers
		(0 "F.Cu" signal "TOP")
		(4 "In1.Cu" signal "GND")
		(6 "In2.Cu" signal "IN1")
		(8 "In3.Cu" signal "GND1")
		(10 "In4.Cu" signal "IN2")
		(12 "In5.Cu" signal "GND2")
		(14 "In6.Cu" signal "IN3")
		(16 "In7.Cu" signal "GND3")
		(18 "In8.Cu" signal "VCC")
		(20 "In9.Cu" signal "VCC1")
		(22 "In10.Cu" signal "GND4")
		(24 "In11.Cu" signal "IN4")
		(26 "In12.Cu" signal "GND5")
		(28 "In13.Cu" signal "IN5")
		(30 "In14.Cu" signal "GND6")
		(32 "In15.Cu" signal "IN6")
		(34 "In16.Cu" signal "GND7")
		(2 "B.Cu" signal "BOTTOM")
		(9 "F.Adhes" user "F.Adhesive")
		(11 "B.Adhes" user "B.Adhesive")
		(13 "F.Paste" user "Package Geometry/Pastemask Top")
		(15 "B.Paste" user "Package Geometry/Pastemask Bottom")
		(5 "F.SilkS" user "Ref Des/Silkscreen Top")
		(7 "B.SilkS" user "Ref Des/Silkscreen Bottom")
		(1 "F.Mask" user "Board Geometry/Soldermask Top")
		(3 "B.Mask" user "Board Geometry/Soldermask Bottom")
		(17 "Dwgs.User" user "User.Drawings")
		(19 "Cmts.User" user "User.Comments")
		(21 "Eco1.User" user "User.Eco1")
		(23 "Eco2.User" user "User.Eco2")
		(25 "Edge.Cuts" user "Board Geometry/Outline")
		(27 "Margin" user)
		(31 "F.CrtYd" user "Package Geometry/Place Bound Top")
		(29 "B.CrtYd" user "Package Geometry/Place Bound Bottom")
		(35 "F.Fab" user "Ref Des/Assembly Top")
		(33 "B.Fab" user "Ref Des/Assembly Bottom")
	)
	(footprint ""
		(layer "B.Cu")
		(at 358.80421 -357.578406)
		(property "Reference" "PR171"
			(at 0 0 0)
			(layer "B.SilkS")
			(hide yes)
			(effects
				(font
					(size 1.27 1.27)
				)
				(justify mirror)
			)
		)
		(property "Value" ""
			(at 0 0 0)
			(layer "B.Fab")
			(effects
				(font
					(size 1.27 1.27)
				)
				(justify mirror)
			)
		)
		(duplicate_pad_numbers_are_jumpers no)
		(fp_line
			(start -0.7874 -0.4064)
			(end -0.7874 0.4064)
			(stroke
				(width 0.1524)
				(type default)
			)
			(layer "B.SilkS")
		)
		(fp_line
			(start -0.7874 0.4064)
			(end 0.7874 0.4064)
			(stroke
				(width 0.1524)
				(type default)
			)
			(layer "B.SilkS")
		)
		(fp_line
			(start 0.7874 -0.4064)
			(end -0.7874 -0.4064)
			(stroke
				(width 0.1524)
				(type default)
			)
			(layer "B.SilkS")
		)
		(fp_line
			(start 0.7874 0.4064)
			(end 0.7874 -0.4064)
			(stroke
				(width 0.1524)
				(type default)
			)
			(layer "B.SilkS")
		)
		(fp_line
			(start -0.67945 -0.3048)
			(end -0.67945 0.3048)
			(stroke
				(width 0.1)
				(type default)
			)
			(layer "B.Fab")
		)
		(fp_line
			(start -0.67945 0.3048)
			(end -0.120396 0.3048)
			(stroke
				(width 0.1)
				(type default)
			)
			(layer "B.Fab")
		)
		(fp_line
			(start -0.12065 -0.3048)
			(end -0.67945 -0.3048)
			(stroke
				(width 0.1)
				(type default)
			)
			(layer "B.Fab")
		)
		(fp_line
			(start -0.12065 -0.2794)
			(end -0.12065 -0.3048)
			(stroke
				(width 0.1)
				(type default)
			)
			(layer "B.Fab")
		)
		(fp_line
			(start -0.120396 0.2794)
			(end 0.12065 0.2794)
			(stroke
				(width 0.1)
				(type default)
			)
			(layer "B.Fab")
		)
		(fp_line
			(start -0.120396 0.3048)
			(end -0.120396 0.2794)
			(stroke
				(width 0.1)
				(type default)
			)
			(layer "B.Fab")
		)
		(fp_line
			(start 0.12065 -0.305054)
			(end 0.12065 -0.2794)
			(stroke
				(width 0.1)
				(type default)
			)
			(layer "B.Fab")
		)
		(fp_line
			(start 0.12065 -0.2794)
			(end -0.12065 -0.2794)
			(stroke
				(width 0.1)
				(type default)
			)
			(layer "B.Fab")
		)
		(fp_line
			(start 0.12065 0.2794)
			(end 0.12065 0.3048)
			(stroke
				(width 0.1)
				(type default)
			)
			(layer "B.Fab")
		)
		(fp_line
			(start 0.12065 0.3048)
			(end 0.67945 0.3048)
			(stroke
				(width 0.1)
				(type default)
			)
			(layer "B.Fab")
		)
		(fp_line
			(start 0.67945 -0.305054)
			(end 0.12065 -0.305054)
			(stroke
				(width 0.1)
				(type default)
			)
			(layer "B.Fab")
		)
		(fp_line
			(start 0.67945 0.3048)
			(end 0.67945 -0.305054)
			(stroke
				(width 0.1)
				(type default)
			)
			(layer "B.Fab")
		)
		(pad "1" smd circle
			(at 0.40005 0 180)
			(size 0 0)
			(layers "B.Cu" "B.Mask" "B.Paste")
			(net "PVCCIN_CPU0_ADDR")
		)
		(pad "2" smd circle
			(at -0.40005 0 180)
			(size 0 0)
			(layers "B.Cu" "B.Mask" "B.Paste")
			(net "GND")
		)
	)
	(footprint ""
		(layer "B.Cu")
		(at 177.443638 -13.762228 90)
		(property "Reference" "R2423"
			(at 0 0 90)
			(layer "B.SilkS")
			(hide yes)
			(effects
				(font
					(size 1.27 1.27)
				)
				(justify mirror)
			)
		)
		(property "Value" ""
			(at 0 0 90)
			(layer "B.Fab")
			(effects
				(font
					(size 1.27 1.27)
				)
				(justify mirror)
			)
		)
		(duplicate_pad_numbers_are_jumpers no)
		(fp_line
			(start 0.7874 -0.4064)
			(end -0.7874 -0.4064)
			(stroke
				(width 0.1524)
				(type default)
			)
			(layer "B.SilkS")
		)
		(fp_line
			(start -0.7874 -0.4064)
			(end -0.7874 0.4064)
			(stroke
				(width 0.1524)
				(type default)
			)
			(layer "B.SilkS")
		)
		(fp_line
			(start 0.7874 0.4064)
			(end 0.7874 -0.4064)
			(stroke
				(width 0.1524)
				(type default)
			)
			(layer "B.SilkS")
		)
		(fp_line
			(start -0.7874 0.4064)
			(end 0.7874 0.4064)
			(stroke
				(width 0.1524)
				(type default)
			)
			(layer "B.SilkS")
		)
		(fp_line
			(start 0.67945 -0.305054)
			(end 0.12065 -0.305054)
			(stroke
				(width 0.1)
				(type default)
			)
			(layer "B.Fab")
		)
		(fp_line
			(start 0.12065 -0.305054)
			(end 0.12065 -0.2794)
			(stroke
				(width 0.1)
				(type default)
			)
			(layer "B.Fab")
		)
		(fp_line
			(start -0.12065 -0.3048)
			(end -0.67945 -0.3048)
			(stroke
				(width 0.1)
				(type default)
			)
			(layer "B.Fab")
		)
		(fp_line
			(start -0.67945 -0.3048)
			(end -0.67945 0.3048)
			(stroke
				(width 0.1)
				(type default)
			)
			(layer "B.Fab")
		)
		(fp_line
			(start 0.12065 -0.2794)
			(end -0.12065 -0.2794)
			(stroke
				(width 0.1)
				(type default)
			)
			(layer "B.Fab")
		)
		(fp_line
			(start -0.12065 -0.2794)
			(end -0.12065 -0.3048)
			(stroke
				(width 0.1)
				(type default)
			)
			(layer "B.Fab")
		)
		(fp_line
			(start 0.12065 0.2794)
			(end 0.12065 0.3048)
			(stroke
				(width 0.1)
				(type default)
			)
			(layer "B.Fab")
		)
		(fp_line
			(start -0.120396 0.2794)
			(end 0.12065 0.2794)
			(stroke
				(width 0.1)
				(type default)
			)
			(layer "B.Fab")
		)
		(fp_line
			(start 0.67945 0.3048)
			(end 0.67945 -0.305054)
			(stroke
				(width 0.1)
				(type default)
			)
			(layer "B.Fab")
		)
		(fp_line
			(start 0.12065 0.3048)
			(end 0.67945 0.3048)
			(stroke
				(width 0.1)
				(type default)
			)
			(layer "B.Fab")
		)
		(fp_line
			(start -0.120396 0.3048)
			(end -0.120396 0.2794)
			(stroke
				(width 0.1)
				(type default)
			)
			(layer "B.Fab")
		)
		(fp_line
			(start -0.67945 0.3048)
			(end -0.120396 0.3048)
			(stroke
				(width 0.1)
				(type default)
			)
			(layer "B.Fab")
		)
		(pad "1" smd circle
			(at 0.40005 0 270)
			(size 0 0)
			(layers "B.Cu" "B.Mask" "B.Paste")
			(net "SMB_SML1_PMBUS_3V3AUX_PCH_SCL")
		)
		(pad "2" smd circle
			(at -0.40005 0 270)
			(size 0 0)
			(layers "B.Cu" "B.Mask" "B.Paste")
			(net "SMB_SML1_PMBUS_3V3AUX_PCH_SCL_R")
		)
	)
	(footprint ""
		(layer "B.Cu")
		(at 119.95912 -255.8542 -90)
		(property "Reference" "C335"
			(at 0 0 90)
			(layer "B.SilkS")
			(hide yes)
			(effects
				(font
					(size 1.27 1.27)
				)
				(justify mirror)
			)
		)
		(property "Value" ""
			(at 0 0 90)
			(layer "B.Fab")
			(effects
				(font
					(size 1.27 1.27)
				)
				(justify mirror)
			)
		)
		(duplicate_pad_numbers_are_jumpers no)
		(fp_line
			(start -1.524 0.762)
			(end 1.524 0.762)
			(stroke
				(width 0.1524)
				(type default)
			)
			(layer "B.SilkS")
		)
		(fp_line
			(start 1.524 0.762)
			(end 1.524 -0.762)
			(stroke
				(width 0.1524)
				(type default)
			)
			(layer "B.SilkS")
		)
		(fp_line
			(start -1.524 -0.762)
			(end -1.524 0.762)
			(stroke
				(width 0.1524)
				(type default)
			)
			(layer "B.SilkS")
		)
		(fp_line
			(start 1.524 -0.762)
			(end -1.524 -0.762)
			(stroke
				(width 0.1524)
				(type default)
			)
			(layer "B.SilkS")
		)
		(fp_line
			(start -1.1049 0.724916)
			(end -1.1049 -0.724916)
			(stroke
				(width 0.1)
				(type default)
			)
			(layer "B.Fab")
		)
		(fp_line
			(start 1.1049 0.724916)
			(end -1.1049 0.724916)
			(stroke
				(width 0.1)
				(type default)
			)
			(layer "B.Fab")
		)
		(fp_line
			(start -1.1049 -0.724916)
			(end 1.1049 -0.724916)
			(stroke
				(width 0.1)
				(type default)
			)
			(layer "B.Fab")
		)
		(fp_line
			(start 1.1049 -0.724916)
			(end 1.1049 0.724916)
			(stroke
				(width 0.1)
				(type default)
			)
			(layer "B.Fab")
		)
		(pad "1" smd rect
			(at 0.889 0 270)
			(size 1.016 1.27)
			(layers "B.Cu" "B.Mask" "B.Paste")
			(net "PVCCIN_CPU1")
		)
		(pad "2" smd rect
			(at -0.889 0 270)
			(size 1.016 1.27)
			(layers "B.Cu" "B.Mask" "B.Paste")
			(net "GND")
		)
	)
)
